# BASEBOARD_FAB2 (Tioga Pass) — schematic netlist excerpt (pin names and nets, part order shuffled) for the footprints in the layout excerpt that follows; sources: Cadence DE-HDL packaged netlist, KiCad conversion of Wiwynn_Tioga_Pass_MB.brd

R8B1  RES  51.1 1.0% CHIP  pkg 0402  page 112 : A = XDP_PCH_TCK1 ; B = GND
R1W18  RES  0.0 5% CHIP  pkg 0402  page 115 : A = USB2_P02_DP_R ; B = USB2_P02_DP
R7G30  RES  68.1K 1% EMPTY  pkg 0402  page 216 : A = VR_PVDDQ_ABC_PH2_OCSET ; B = GND

(kicad_pcb
	(version 20260206)
	(generator "pcbnew")
	(generator_version "10.0")
	(general
		(thickness 1.6)
		(legacy_teardrops no)
	)
	(paper "A4")
	(title_block
		(title "Wiwynn_Tioga_Pass_MB.brd")
		(comment 1 "Tioga Pass / footprints 626-628 of 4770")
	)
	(layers
		(0 "F.Cu" signal "TOP")
		(4 "In1.Cu" signal "L2GND")
		(6 "In2.Cu" signal "L3")
		(8 "In3.Cu" signal "L4GND")
		(10 "In4.Cu" signal "L5")
		(12 "In5.Cu" signal "L6GND")
		(14 "In6.Cu" signal "L7VCC")
		(16 "In7.Cu" signal "L8VCC")
		(18 "In8.Cu" signal "L9GND")
		(20 "In9.Cu" signal "L10")
		(22 "In10.Cu" signal "L11GND")
		(24 "In11.Cu" signal "L12")
		(26 "In12.Cu" signal "L13GND")
		(2 "B.Cu" signal "BOTTOM")
		(9 "F.Adhes" user "F.Adhesive")
		(11 "B.Adhes" user "B.Adhesive")
		(13 "F.Paste" user "Package Geometry/Pastemask Top")
		(15 "B.Paste" user "Package Geometry/Pastemask Bottom")
		(5 "F.SilkS" user "Ref Des/Silkscreen Top")
		(7 "B.SilkS" user "Ref Des/Silkscreen Bottom")
		(1 "F.Mask" user "Board Geometry/Soldermask Top")
		(3 "B.Mask" user "Board Geometry/Soldermask Bottom")
		(17 "Dwgs.User" user "User.Drawings")
		(19 "Cmts.User" user "User.Comments")
		(21 "Eco1.User" user "User.Eco1")
		(23 "Eco2.User" user "User.Eco2")
		(25 "Edge.Cuts" user "Board Geometry/Outline")
		(27 "Margin" user)
		(31 "F.CrtYd" user "Package Geometry/Place Bound Top")
		(29 "B.CrtYd" user "Package Geometry/Place Bound Bottom")
		(35 "F.Fab" user "Ref Des/Assembly Top")
		(33 "B.Fab" user "Ref Des/Assembly Bottom")
	)
	(footprint ""
		(layer "F.Cu")
		(at 412.632652 -134.747 180)
		(property "Reference" "R8B1"
			(at 0 0 180)
			(layer "F.SilkS")
			(hide yes)
			(effects
				(font
					(size 1.27 1.27)
				)
			)
		)
		(property "Value" ""
			(at 0 0 180)
			(layer "F.Fab")
			(effects
				(font
					(size 1.27 1.27)
				)
			)
		)
		(duplicate_pad_numbers_are_jumpers no)
		(fp_poly
			(pts
				(xy -0.2794 -0.1016) (xy 0.2794 -0.1016) (xy 0.2794 0.9906) (xy -0.2794 0.9906)
			)
			(stroke
				(width 0)
				(type default)
			)
			(fill no)
			(layer "F.CrtYd")
		)
		(fp_line
			(start 0.2794 0.9906)
			(end 0.2794 -0.1016)
			(stroke
				(width 0.1)
				(type default)
			)
			(layer "F.Fab")
		)
		(fp_line
			(start 0.2794 -0.1016)
			(end -0.2794 -0.1016)
			(stroke
				(width 0.1)
				(type default)
			)
			(layer "F.Fab")
		)
		(fp_line
			(start -0.2794 0.9906)
			(end 0.2794 0.9906)
			(stroke
				(width 0.1)
				(type default)
			)
			(layer "F.Fab")
		)
		(fp_line
			(start -0.2794 -0.1016)
			(end -0.2794 0.9906)
			(stroke
				(width 0.1)
				(type default)
			)
			(layer "F.Fab")
		)
		(pad "1" smd rect
			(at 0 0 180)
			(size 0.508 0.508)
			(layers "F.Cu" "F.Mask" "F.Paste")
			(net "XDP_PCH_TCK1")
		)
		(pad "2" smd rect
			(at 0 0.889 180)
			(size 0.508 0.508)
			(layers "F.Cu" "F.Mask" "F.Paste")
			(net "GND")
		)
		(zone
			(layer "F.Cu")
			(hatch none 0.5)
			(connect_pads
				(clearance 0)
			)
			(min_thickness 0.25)
			(keepout
				(tracks not_allowed)
				(vias allowed)
				(pads allowed)
				(copperpour not_allowed)
				(footprints allowed)
			)
			(placement
				(enabled no)
				(sheetname "")
			)
			(fill
				(thermal_gap 0.5)
				(thermal_bridge_width 0.5)
				(island_removal_mode 0)
			)
			(polygon
				(pts
					(xy 412.886652 -135.382) (xy 412.378652 -135.382) (xy 412.378652 -135.001) (xy 412.886652 -135.001)
				)
			)
		)
		(zone
			(layer "F.Cu")
			(hatch none 0.5)
			(connect_pads
				(clearance 0)
			)
			(min_thickness 0.25)
			(keepout
				(tracks allowed)
				(vias not_allowed)
				(pads allowed)
				(copperpour not_allowed)
				(footprints allowed)
			)
			(placement
				(enabled no)
				(sheetname "")
			)
			(fill
				(thermal_gap 0.5)
				(thermal_bridge_width 0.5)
				(island_removal_mode 0)
			)
			(polygon
				(pts
					(xy 412.886652 -135.001) (xy 412.378652 -135.001) (xy 412.378652 -135.382) (xy 412.886652 -135.382)
				)
			)
		)
	)
	(footprint ""
		(layer "F.Cu")
		(at 406.516078 -120.271032 90)
		(property "Reference" "R1W18"
			(at -0.8382 -0.67818 90)
			(unlocked yes)
			(layer "F.SilkS")
			(effects
				(font
					(size 0.4064 0.254)
					(thickness 0.1524)
				)
				(justify left)
			)
		)
		(property "Value" ""
			(at 0 0 90)
			(layer "F.Fab")
			(effects
				(font
					(size 1.27 1.27)
				)
			)
		)
		(duplicate_pad_numbers_are_jumpers no)
		(fp_poly
			(pts
				(xy -0.2794 -0.1016) (xy 0.2794 -0.1016) (xy 0.2794 0.9906) (xy -0.2794 0.9906)
			)
			(stroke
				(width 0)
				(type default)
			)
			(fill no)
			(layer "F.CrtYd")
		)
		(fp_line
			(start 0.2794 -0.1016)
			(end -0.2794 -0.1016)
			(stroke
				(width 0.1)
				(type default)
			)
			(layer "F.Fab")
		)
		(fp_line
			(start -0.2794 -0.1016)
			(end -0.2794 0.9906)
			(stroke
				(width 0.1)
				(type default)
			)
			(layer "F.Fab")
		)
		(fp_line
			(start 0.2794 0.9906)
			(end 0.2794 -0.1016)
			(stroke
				(width 0.1)
				(type default)
			)
			(layer "F.Fab")
		)
		(fp_line
			(start -0.2794 0.9906)
			(end 0.2794 0.9906)
			(stroke
				(width 0.1)
				(type default)
			)
			(layer "F.Fab")
		)
		(pad "1" smd rect
			(at 0 0 90)
			(size 0.508 0.508)
			(layers "F.Cu" "F.Mask" "F.Paste")
			(net "USB2_P02_DP_R")
		)
		(pad "2" smd rect
			(at 0 0.889 90)
			(size 0.508 0.508)
			(layers "F.Cu" "F.Mask" "F.Paste")
			(net "USB2_P02_DP")
		)
		(zone
			(layer "F.Cu")
			(hatch none 0.5)
			(connect_pads
				(clearance 0)
			)
			(min_thickness 0.25)
			(keepout
				(tracks allowed)
				(vias not_allowed)
				(pads allowed)
				(copperpour not_allowed)
				(footprints allowed)
			)
			(placement
				(enabled no)
				(sheetname "")
			)
			(fill
				(thermal_gap 0.5)
				(thermal_bridge_width 0.5)
				(island_removal_mode 0)
			)
			(polygon
				(pts
					(xy 406.770078 -120.017032) (xy 406.770078 -120.525032) (xy 407.151078 -120.525032) (xy 407.151078 -120.017032)
				)
			)
		)
		(zone
			(layer "F.Cu")
			(hatch none 0.5)
			(connect_pads
				(clearance 0)
			)
			(min_thickness 0.25)
			(keepout
				(tracks not_allowed)
				(vias allowed)
				(pads allowed)
				(copperpour not_allowed)
				(footprints allowed)
			)
			(placement
				(enabled no)
				(sheetname "")
			)
			(fill
				(thermal_gap 0.5)
				(thermal_bridge_width 0.5)
				(island_removal_mode 0)
			)
			(polygon
				(pts
					(xy 407.151078 -120.017032) (xy 407.151078 -120.525032) (xy 406.770078 -120.525032) (xy 406.770078 -120.017032)
				)
			)
		)
	)
	(footprint ""
		(layer "F.Cu")
		(at 352.424238 -0.124206)
		(property "Reference" "R7G30"
			(at 0 0 0)
			(layer "F.SilkS")
			(hide yes)
			(effects
				(font
					(size 1.27 1.27)
				)
			)
		)
		(property "Value" ""
			(at 0 0 0)
			(layer "F.Fab")
			(effects
				(font
					(size 1.27 1.27)
				)
			)
		)
		(duplicate_pad_numbers_are_jumpers no)
		(fp_poly
			(pts
				(xy -0.2794 -0.1016) (xy 0.2794 -0.1016) (xy 0.2794 0.9906) (xy -0.2794 0.9906)
			)
			(stroke
				(width 0)
				(type default)
			)
			(fill no)
			(layer "F.CrtYd")
		)
		(fp_line
			(start -0.2794 -0.1016)
			(end -0.2794 0.9906)
			(stroke
				(width 0.1)
				(type default)
			)
			(layer "F.Fab")
		)
		(fp_line
			(start -0.2794 0.9906)
			(end 0.2794 0.9906)
			(stroke
				(width 0.1)
				(type default)
			)
			(layer "F.Fab")
		)
		(fp_line
			(start 0.2794 -0.1016)
			(end -0.2794 -0.1016)
			(stroke
				(width 0.1)
				(type default)
			)
			(layer "F.Fab")
		)
		(fp_line
			(start 0.2794 0.9906)
			(end 0.2794 -0.1016)
			(stroke
				(width 0.1)
				(type default)
			)
			(layer "F.Fab")
		)
		(pad "1" smd rect
			(at 0 0)
			(size 0.508 0.508)
			(layers "F.Cu" "F.Mask" "F.Paste")
			(net "VR_PVDDQ_ABC_PH2_OCSET")
		)
		(pad "2" smd rect
			(at 0 0.889)
			(size 0.508 0.508)
			(layers "F.Cu" "F.Mask" "F.Paste")
			(net "GND")
		)
		(zone
			(layer "F.Cu")
			(hatch none 0.5)
			(connect_pads
				(clearance 0)
			)
			(min_thickness 0.25)
			(keepout
				(tracks allowed)
				(vias not_allowed)
				(pads allowed)
				(copperpour not_allowed)
				(footprints allowed)
			)
			(placement
				(enabled no)
				(sheetname "")
			)
			(fill
				(thermal_gap 0.5)
				(thermal_bridge_width 0.5)
				(island_removal_mode 0)
			)
			(polygon
				(pts
					(xy 352.170238 0.129794) (xy 352.678238 0.129794) (xy 352.678238 0.510794) (xy 352.170238 0.510794)
				)
			)
		)
		(zone
			(layer "F.Cu")
			(hatch none 0.5)
			(connect_pads
				(clearance 0)
			)
			(min_thickness 0.25)
			(keepout
				(tracks not_allowed)
				(vias allowed)
				(pads allowed)
				(copperpour not_allowed)
				(footprints allowed)
			)
			(placement
				(enabled no)
				(sheetname "")
			)
			(fill
				(thermal_gap 0.5)
				(thermal_bridge_width 0.5)
				(island_removal_mode 0)
			)
			(polygon
				(pts
					(xy 352.170238 0.510794) (xy 352.678238 0.510794) (xy 352.678238 0.129794) (xy 352.170238 0.129794)
				)
			)
		)
	)
)
